# T6G (Grand Teton) — schematic netlist excerpt (pin names and nets, part order shuffled) for the footprints in the layout excerpt that follows; sources: Cadence DE-HDL packaged netlist, KiCad conversion of 04192023_DAF0TMB3IC0_F0TG_MB_C_brd_V02_OCP.brd

U6005  ISL28022FRZT  ISL28022FRZ-T IC  pkg QFN16_TH_0-5_3X3XH  page 271
  A1  = HSC_TYPE_ADC_A1
  A0  = HSC_TYPE_ADC_A0
  \ext_clk||int\  = HSC_TYPE_ADC_ALERT
  \sda||smbdat\  = SMB_HSC_TYPE_ADC_SDA
  \scl|||smbclk\  = SMB_HSC_TYPE_ADC_SCL
  NC0  = NC_HSC_TYPE_NC0
  NC1  = NC_HSC_TYPE_NC1
  NC2  = NC_HSC_TYPE_NC2
  VCC  = P3V3_AUX
  GND  = GND
  VBUS  = HSC_TYPE_ADC
  VINM  = NC_HSC_TYPE_VINM
  VINP  = NC_HSC_TYPE_VINP
  NC3  = NC_HSC_TYPE_NC3
  NC4  = NC_HSC_TYPE_NC4
  NC5  = NC_HSC_TYPE_NC5
  TH_GND  = GND

(kicad_pcb
	(version 20260206)
	(generator "pcbnew")
	(generator_version "10.0")
	(general
		(thickness 1.6)
		(legacy_teardrops no)
	)
	(paper "A4")
	(title_block
		(title "04192023_DAF0TMB3IC0_F0TG_MB_C_brd_V02_OCP.brd")
		(comment 1 "Grand Teton / footprints 1537-1537 of 8354")
	)
	(layers
		(0 "F.Cu" signal "TOP")
		(4 "In1.Cu" signal "GND")
		(6 "In2.Cu" signal "IN1")
		(8 "In3.Cu" signal "GND1")
		(10 "In4.Cu" signal "IN2")
		(12 "In5.Cu" signal "GND2")
		(14 "In6.Cu" signal "IN3")
		(16 "In7.Cu" signal "GND3")
		(18 "In8.Cu" signal "VCC")
		(20 "In9.Cu" signal "VCC1")
		(22 "In10.Cu" signal "GND4")
		(24 "In11.Cu" signal "IN4")
		(26 "In12.Cu" signal "GND5")
		(28 "In13.Cu" signal "IN5")
		(30 "In14.Cu" signal "GND6")
		(32 "In15.Cu" signal "IN6")
		(34 "In16.Cu" signal "GND7")
		(2 "B.Cu" signal "BOTTOM")
		(9 "F.Adhes" user "F.Adhesive")
		(11 "B.Adhes" user "B.Adhesive")
		(13 "F.Paste" user "Package Geometry/Pastemask Top")
		(15 "B.Paste" user "Package Geometry/Pastemask Bottom")
		(5 "F.SilkS" user "Ref Des/Silkscreen Top")
		(7 "B.SilkS" user "Ref Des/Silkscreen Bottom")
		(1 "F.Mask" user "Board Geometry/Soldermask Top")
		(3 "B.Mask" user "Board Geometry/Soldermask Bottom")
		(17 "Dwgs.User" user "User.Drawings")
		(19 "Cmts.User" user "User.Comments")
		(21 "Eco1.User" user "User.Eco1")
		(23 "Eco2.User" user "User.Eco2")
		(25 "Edge.Cuts" user "Board Geometry/Outline")
		(27 "Margin" user)
		(31 "F.CrtYd" user "Package Geometry/Place Bound Top")
		(29 "B.CrtYd" user "Package Geometry/Place Bound Bottom")
		(35 "F.Fab" user "Ref Des/Assembly Top")
		(33 "B.Fab" user "Ref Des/Assembly Bottom")
	)
	(footprint ""
		(layer "F.Cu")
		(at 429.024542 -428.30623 90)
		(property "Reference" "U6005"
			(at -0.025908 5.518658 90)
			(unlocked yes)
			(layer "F.SilkS")
			(effects
				(font
					(size 0.7874 0.5842)
					(thickness 0.1524)
				)
			)
		)
		(property "Value" ""
			(at 0 0 90)
			(layer "F.Fab")
			(effects
				(font
					(size 1.27 1.27)
				)
			)
		)
		(duplicate_pad_numbers_are_jumpers no)
		(fp_line
			(start 1.500124 -1.500124)
			(end 1.500124 -1.004062)
			(stroke
				(width 0.1524)
				(type default)
			)
			(layer "F.SilkS")
		)
		(fp_line
			(start 1.004062 -1.500124)
			(end 1.500124 -1.500124)
			(stroke
				(width 0.1524)
				(type default)
			)
			(layer "F.SilkS")
		)
		(fp_line
			(start -1.500124 -1.500124)
			(end -1.004062 -1.500124)
			(stroke
				(width 0.1524)
				(type default)
			)
			(layer "F.SilkS")
		)
		(fp_line
			(start -1.500124 -1.004062)
			(end -1.500124 -1.500124)
			(stroke
				(width 0.1524)
				(type default)
			)
			(layer "F.SilkS")
		)
		(fp_line
			(start 1.500124 1.004062)
			(end 1.500124 1.500124)
			(stroke
				(width 0.1524)
				(type default)
			)
			(layer "F.SilkS")
		)
		(fp_line
			(start 1.500124 1.500124)
			(end 1.004062 1.500124)
			(stroke
				(width 0.1524)
				(type default)
			)
			(layer "F.SilkS")
		)
		(fp_line
			(start -1.004062 1.500124)
			(end -1.500124 1.500124)
			(stroke
				(width 0.1524)
				(type default)
			)
			(layer "F.SilkS")
		)
		(fp_line
			(start -1.500124 1.500124)
			(end -1.500124 1.004062)
			(stroke
				(width 0.1524)
				(type default)
			)
			(layer "F.SilkS")
		)
		(fp_poly
			(pts
				(xy -1.862328 -1.148588) (xy -2.88036 -1.652778) (xy -2.069592 -2.265426)
			)
			(stroke
				(width 0)
				(type default)
			)
			(fill yes)
			(layer "F.SilkS")
		)
		(fp_line
			(start 1.500124 -1.500124)
			(end 1.500124 1.500124)
			(stroke
				(width 0.1)
				(type default)
			)
			(layer "F.Fab")
		)
		(fp_line
			(start -1.500124 -1.500124)
			(end 1.500124 -1.500124)
			(stroke
				(width 0.1)
				(type default)
			)
			(layer "F.Fab")
		)
		(fp_line
			(start 1.500124 1.500124)
			(end -1.500124 1.500124)
			(stroke
				(width 0.1)
				(type default)
			)
			(layer "F.Fab")
		)
		(fp_line
			(start -1.500124 1.500124)
			(end -1.500124 -1.500124)
			(stroke
				(width 0.1)
				(type default)
			)
			(layer "F.Fab")
		)
		(fp_poly
			(pts
				(xy -2.847848 -1.258062) (xy -2.847848 -0.242062) (xy -1.831848 -0.750062)
			)
			(stroke
				(width 0)
				(type default)
			)
			(fill yes)
			(layer "F.Fab")
		)
		(pad "1" smd rect
			(at -1.400048 -0.750062)
			(size 0.2286 0.6096)
			(layers "F.Cu" "F.Mask" "F.Paste")
			(net "HSC_TYPE_ADC_A1")
		)
		(pad "2" smd rect
			(at -1.400048 -0.249936)
			(size 0.2286 0.6096)
			(layers "F.Cu" "F.Mask" "F.Paste")
			(net "HSC_TYPE_ADC_A0")
		)
		(pad "3" smd rect
			(at -1.400048 0.249936)
			(size 0.2286 0.6096)
			(layers "F.Cu" "F.Mask" "F.Paste")
			(net "HSC_TYPE_ADC_ALERT")
		)
		(pad "4" smd rect
			(at -1.400048 0.750062)
			(size 0.2286 0.6096)
			(layers "F.Cu" "F.Mask" "F.Paste")
			(net "SMB_HSC_TYPE_ADC_SDA")
		)
		(pad "5" smd rect
			(at -0.750062 1.400048 90)
			(size 0.2286 0.6096)
			(layers "F.Cu" "F.Mask" "F.Paste")
			(net "SMB_HSC_TYPE_ADC_SCL")
		)
		(pad "6" smd rect
			(at -0.249936 1.400048 90)
			(size 0.2286 0.6096)
			(layers "F.Cu" "F.Mask" "F.Paste")
			(net "NC_HSC_TYPE_NC0")
		)
		(pad "7" smd rect
			(at 0.249936 1.400048 90)
			(size 0.2286 0.6096)
			(layers "F.Cu" "F.Mask" "F.Paste")
			(net "NC_HSC_TYPE_NC1")
		)
		(pad "8" smd rect
			(at 0.750062 1.400048 90)
			(size 0.2286 0.6096)
			(layers "F.Cu" "F.Mask" "F.Paste")
			(net "NC_HSC_TYPE_NC2")
		)
		(pad "9" smd rect
			(at 1.400048 0.750062)
			(size 0.2286 0.6096)
			(layers "F.Cu" "F.Mask" "F.Paste")
			(net "P3V3_AUX")
		)
		(pad "10" smd rect
			(at 1.400048 0.249936)
			(size 0.2286 0.6096)
			(layers "F.Cu" "F.Mask" "F.Paste")
			(net "GND")
		)
		(pad "11" smd rect
			(at 1.400048 -0.249936)
			(size 0.2286 0.6096)
			(layers "F.Cu" "F.Mask" "F.Paste")
			(net "HSC_TYPE_ADC")
		)
		(pad "12" smd rect
			(at 1.400048 -0.750062)
			(size 0.2286 0.6096)
			(layers "F.Cu" "F.Mask" "F.Paste")
			(net "NC_HSC_TYPE_VINM")
		)
		(pad "13" smd rect
			(at 0.750062 -1.400048 90)
			(size 0.2286 0.6096)
			(layers "F.Cu" "F.Mask" "F.Paste")
			(net "NC_HSC_TYPE_VINP")
		)
		(pad "14" smd rect
			(at 0.249936 -1.400048 90)
			(size 0.2286 0.6096)
			(layers "F.Cu" "F.Mask" "F.Paste")
			(net "NC_HSC_TYPE_NC3")
		)
		(pad "15" smd rect
			(at -0.249936 -1.400048 90)
			(size 0.2286 0.6096)
			(layers "F.Cu" "F.Mask" "F.Paste")
			(net "NC_HSC_TYPE_NC4")
		)
		(pad "16" smd rect
			(at -0.750062 -1.400048 90)
			(size 0.2286 0.6096)
			(layers "F.Cu" "F.Mask" "F.Paste")
			(net "NC_HSC_TYPE_NC5")
		)
		(pad "TH" smd rect
			(at 0 0 90)
			(size 1.7018 1.7018)
			(layers "F.Cu" "F.Mask" "F.Paste")
			(net "GND")
		)
		(zone
			(layer "F.Cu")
			(hatch none 0.5)
			(connect_pads
				(clearance 0)
			)
			(min_thickness 0.25)
			(keepout
				(tracks not_allowed)
				(vias allowed)
				(pads allowed)
				(copperpour not_allowed)
				(footprints allowed)
			)
			(placement
				(enabled no)
				(sheetname "")
			)
			(fill
				(thermal_gap 0.5)
				(thermal_bridge_width 0.5)
				(island_removal_mode 0)
			)
			(polygon
				(pts
					(xy 429.024542 -427.261782) (xy 429.024542 -427.40453) (xy 429.926242 -427.40453) (xy 429.926242 -429.20793)
					(xy 429.538638 -429.20793) (xy 429.538638 -429.350678) (xy 430.06899 -429.350678) (xy 430.06899 -427.261782)
				)
			)
		)
	)
)
